(kicad_pcb
	(version 20260206)
	(generator "pcbnew")
	(generator_version "10.0")
	(general
		(thickness 1.6)
		(legacy_teardrops no)
	)
	(paper "A4")
	(title_block
		(title "Bryce Canyon_IOM_IOC_16318-2_OCP.brd")
		(comment 1 "Bryce Canyon / footprints 989-996 of 1605")
	)
	(layers
		(0 "F.Cu" signal "TOP")
		(4 "In1.Cu" signal "L2GND")
		(6 "In2.Cu" signal "L3")
		(8 "In3.Cu" signal "L4VCC")
		(10 "In4.Cu" signal "L5VCC")
		(12 "In5.Cu" signal "L6")
		(14 "In6.Cu" signal "L7GND")
		(2 "B.Cu" signal "BOTTOM")
		(9 "F.Adhes" user "F.Adhesive")
		(11 "B.Adhes" user "B.Adhesive")
		(13 "F.Paste" user "Package Geometry/Pastemask Top")
		(15 "B.Paste" user "Package Geometry/Pastemask Bottom")
		(5 "F.SilkS" user "Ref Des/Silkscreen Top")
		(7 "B.SilkS" user "Ref Des/Silkscreen Bottom")
		(1 "F.Mask" user "Board Geometry/Soldermask Top")
		(3 "B.Mask" user "Board Geometry/Soldermask Bottom")
		(17 "Dwgs.User" user "User.Drawings")
		(19 "Cmts.User" user "User.Comments")
		(21 "Eco1.User" user "User.Eco1")
		(23 "Eco2.User" user "User.Eco2")
		(25 "Edge.Cuts" user "Board Geometry/Outline")
		(27 "Margin" user)
		(31 "F.CrtYd" user "Package Geometry/Place Bound Top")
		(29 "B.CrtYd" user "Package Geometry/Place Bound Bottom")
		(35 "F.Fab" user "Ref Des/Assembly Top")
		(33 "B.Fab" user "Ref Des/Assembly Bottom")
	)
	(footprint ""
		(layer "B.Cu")
		(at 89.662 -155.6004 90)
		(property "Reference" "C12"
			(at 0 0 90)
			(layer "B.SilkS")
			(hide yes)
			(effects
				(font
					(size 1.27 1.27)
				)
				(justify mirror)
			)
		)
		(property "Value" "SC1U16V2KX-7-GP"
			(at -1.7526 -1.6002 90)
			(unlocked yes)
			(layer "B.Fab")
			(hide yes)
			(effects
				(font
					(size 1.016 1.016)
					(thickness 0.1524)
				)
				(justify mirror)
			)
		)
		(property "Device Type" "C402-TO0D2H24"
			(at -1.7526 -3.1242 90)
			(unlocked yes)
			(layer "B.Fab")
			(hide yes)
			(effects
				(font
					(size 1.016 1.016)
					(thickness 0.1524)
				)
				(justify mirror)
			)
		)
		(duplicate_pad_numbers_are_jumpers no)
		(fp_rect
			(start 0.4826 0.889)
			(end -0.4826 -0.889)
			(stroke
				(width 0)
				(type default)
			)
			(fill no)
			(layer "B.CrtYd")
		)
		(fp_rect
			(start 0.4826 0.889)
			(end -0.4826 -0.889)
			(stroke
				(width 0)
				(type default)
			)
			(fill no)
			(layer "B.Fab")
		)
		(pad "1" smd custom
			(at 0 -0.4572 270)
			(size 0.1524 0.1524)
			(layers "B.Cu" "B.Mask" "B.Paste")
			(net "P3V3_STBY")
			(options
				(clearance outline)
				(anchor circle)
			)
			(primitives
				(gr_poly
					(pts
						(arc
							(start -0.254 -0.3048)
							(mid -0.325842 -0.275042)
							(end -0.3556 -0.2032)
						)
						(arc
							(start -0.3556 0.2032)
							(mid -0.325842 0.275042)
							(end -0.254 0.3048)
						)
						(arc
							(start 0.254 0.3048)
							(mid 0.325842 0.275042)
							(end 0.3556 0.2032)
						)
						(arc
							(start 0.3556 -0.2032)
							(mid 0.325842 -0.275042)
							(end 0.254 -0.3048)
						)
					)
					(width 0)
					(fill yes)
				)
			)
		)
		(pad "2" smd custom
			(at 0 0.4572 270)
			(size 0.1524 0.1524)
			(layers "B.Cu" "B.Mask" "B.Paste")
			(net "GND")
			(options
				(clearance outline)
				(anchor circle)
			)
			(primitives
				(gr_poly
					(pts
						(arc
							(start -0.254 -0.3048)
							(mid -0.325842 -0.275042)
							(end -0.3556 -0.2032)
						)
						(arc
							(start -0.3556 0.2032)
							(mid -0.325842 0.275042)
							(end -0.254 0.3048)
						)
						(arc
							(start 0.254 0.3048)
							(mid 0.325842 0.275042)
							(end 0.3556 0.2032)
						)
						(arc
							(start 0.3556 -0.2032)
							(mid 0.325842 -0.275042)
							(end 0.254 -0.3048)
						)
					)
					(width 0)
					(fill yes)
				)
			)
		)
	)
	(footprint ""
		(layer "B.Cu")
		(at 38.038278 -153.050748 -90)
		(property "Reference" "R321"
			(at 0 0 90)
			(layer "B.SilkS")
			(hide yes)
			(effects
				(font
					(size 1.27 1.27)
				)
				(justify mirror)
			)
		)
		(property "Value" "0R2J-2-GP"
			(at -0.064008 -3.993896 270)
			(unlocked yes)
			(layer "B.Fab")
			(hide yes)
			(effects
				(font
					(size 1.016 1.016)
					(thickness 0.1524)
				)
				(justify mirror)
			)
		)
		(property "Device Type" "R402H16"
			(at -0.064008 -5.517896 270)
			(unlocked yes)
			(layer "B.Fab")
			(hide yes)
			(effects
				(font
					(size 1.016 1.016)
					(thickness 0.1524)
				)
				(justify mirror)
			)
		)
		(duplicate_pad_numbers_are_jumpers no)
		(fp_line
			(start -0.508 -0.9398)
			(end 0.508 -0.9398)
			(stroke
				(width 0.1524)
				(type default)
			)
			(layer "B.SilkS")
		)
		(fp_line
			(start 0.508 -0.9398)
			(end 0.508 0.9398)
			(stroke
				(width 0.1524)
				(type default)
			)
			(layer "B.SilkS")
		)
		(fp_rect
			(start 0.508 0.9398)
			(end -0.508 -0.9398)
			(stroke
				(width 0)
				(type default)
			)
			(fill no)
			(layer "B.CrtYd")
		)
		(fp_rect
			(start 0.508 0.9398)
			(end -0.508 -0.9398)
			(stroke
				(width 0)
				(type default)
			)
			(fill no)
			(layer "B.Fab")
		)
		(pad "1" smd custom
			(at 0 -0.4445 90)
			(size 0.1397 0.1397)
			(layers "B.Cu" "B.Mask" "B.Paste")
			(net "SCC_B_HB_IN_R")
			(options
				(clearance outline)
				(anchor circle)
			)
			(primitives
				(gr_poly
					(pts
						(arc
							(start -0.1778 0.2794)
							(mid -0.249642 0.249642)
							(end -0.2794 0.1778)
						)
						(arc
							(start -0.2794 -0.1778)
							(mid -0.249642 -0.249642)
							(end -0.1778 -0.2794)
						)
						(arc
							(start 0.1778 -0.2794)
							(mid 0.249642 -0.249642)
							(end 0.2794 -0.1778)
						)
						(arc
							(start 0.2794 0.1778)
							(mid 0.249642 0.249642)
							(end 0.1778 0.2794)
						)
					)
					(width 0)
					(fill yes)
				)
			)
		)
		(pad "2" smd custom
			(at 0 0.4445 90)
			(size 0.1397 0.1397)
			(layers "B.Cu" "B.Mask" "B.Paste")
			(net "SCC_RMT_HEARTBEAT")
			(options
				(clearance outline)
				(anchor circle)
			)
			(primitives
				(gr_poly
					(pts
						(arc
							(start -0.1778 0.2794)
							(mid -0.249642 0.249642)
							(end -0.2794 0.1778)
						)
						(arc
							(start -0.2794 -0.1778)
							(mid -0.249642 -0.249642)
							(end -0.1778 -0.2794)
						)
						(arc
							(start 0.1778 -0.2794)
							(mid 0.249642 -0.249642)
							(end 0.2794 -0.1778)
						)
						(arc
							(start 0.2794 0.1778)
							(mid 0.249642 0.249642)
							(end 0.1778 0.2794)
						)
					)
					(width 0)
					(fill yes)
				)
			)
		)
	)
	(footprint ""
		(layer "B.Cu")
		(at 178.098704 -140.824966 90)
		(property "Reference" "C157"
			(at 0 0 90)
			(layer "B.SilkS")
			(hide yes)
			(effects
				(font
					(size 1.27 1.27)
				)
				(justify mirror)
			)
		)
		(property "Value" "SC4D7U25V5KX-1-GP"
			(at 0.0762 -6.1214 90)
			(unlocked yes)
			(layer "B.Fab")
			(hide yes)
			(effects
				(font
					(size 1.016 1.016)
					(thickness 0.1524)
				)
				(justify mirror)
			)
		)
		(property "Device Type" "C805H58"
			(at 0.0762 -8.1534 90)
			(unlocked yes)
			(layer "B.Fab")
			(hide yes)
			(effects
				(font
					(size 1.016 1.016)
					(thickness 0.1524)
				)
				(justify mirror)
			)
		)
		(duplicate_pad_numbers_are_jumpers no)
		(fp_line
			(start -0.635 0)
			(end 0.635 0)
			(stroke
				(width 0.508)
				(type default)
			)
			(layer "B.SilkS")
		)
		(fp_rect
			(start 0.9652 1.778)
			(end -0.9652 -1.778)
			(stroke
				(width 0)
				(type default)
			)
			(fill no)
			(layer "B.CrtYd")
		)
		(fp_poly
			(pts
				(xy 0.9652 -1.778) (xy -0.9652 -1.778) (xy -0.9652 1.778) (xy 0.9652 1.778)
			)
			(stroke
				(width 0)
				(type default)
			)
			(fill no)
			(layer "B.Fab")
		)
		(pad "1" smd rect
			(at 0 -0.9652 270)
			(size 1.397 1.143)
			(layers "B.Cu" "B.Mask" "B.Paste")
			(net "P12V_STBY_VDD_PU1")
		)
		(pad "2" smd rect
			(at 0 0.9652 270)
			(size 1.397 1.143)
			(layers "B.Cu" "B.Mask" "B.Paste")
			(net "GND")
		)
	)
	(footprint ""
		(layer "B.Cu")
		(at 12.091924 -138.144504 90)
		(property "Reference" "R247"
			(at 0 0 90)
			(layer "B.SilkS")
			(hide yes)
			(effects
				(font
					(size 1.27 1.27)
				)
				(justify mirror)
			)
		)
		(property "Value" "120R2F-GP"
			(at -0.064008 -3.993896 90)
			(unlocked yes)
			(layer "B.Fab")
			(hide yes)
			(effects
				(font
					(size 1.016 1.016)
					(thickness 0.1524)
				)
				(justify mirror)
			)
		)
		(property "Device Type" "R402H16"
			(at -0.064008 -5.517896 90)
			(unlocked yes)
			(layer "B.Fab")
			(hide yes)
			(effects
				(font
					(size 1.016 1.016)
					(thickness 0.1524)
				)
				(justify mirror)
			)
		)
		(duplicate_pad_numbers_are_jumpers no)
		(fp_line
			(start 0.508 -0.9398)
			(end 0.508 0.9398)
			(stroke
				(width 0.1524)
				(type default)
			)
			(layer "B.SilkS")
		)
		(fp_line
			(start -0.508 -0.9398)
			(end 0.508 -0.9398)
			(stroke
				(width 0.1524)
				(type default)
			)
			(layer "B.SilkS")
		)
		(fp_rect
			(start 0.508 0.9398)
			(end -0.508 -0.9398)
			(stroke
				(width 0)
				(type default)
			)
			(fill no)
			(layer "B.CrtYd")
		)
		(fp_rect
			(start 0.508 0.9398)
			(end -0.508 -0.9398)
			(stroke
				(width 0)
				(type default)
			)
			(fill no)
			(layer "B.Fab")
		)
		(pad "1" smd custom
			(at 0 -0.4445 270)
			(size 0.1397 0.1397)
			(layers "B.Cu" "B.Mask" "B.Paste")
			(net "MEMA_6")
			(options
				(clearance outline)
				(anchor circle)
			)
			(primitives
				(gr_poly
					(pts
						(arc
							(start -0.1778 0.2794)
							(mid -0.249642 0.249642)
							(end -0.2794 0.1778)
						)
						(arc
							(start -0.2794 -0.1778)
							(mid -0.249642 -0.249642)
							(end -0.1778 -0.2794)
						)
						(arc
							(start 0.1778 -0.2794)
							(mid 0.249642 -0.249642)
							(end 0.2794 -0.1778)
						)
						(arc
							(start 0.2794 0.1778)
							(mid 0.249642 0.249642)
							(end 0.1778 0.2794)
						)
					)
					(width 0)
					(fill yes)
				)
			)
		)
		(pad "2" smd custom
			(at 0 0.4445 270)
			(size 0.1397 0.1397)
			(layers "B.Cu" "B.Mask" "B.Paste")
			(net "P1V2_STBY")
			(options
				(clearance outline)
				(anchor circle)
			)
			(primitives
				(gr_poly
					(pts
						(arc
							(start -0.1778 0.2794)
							(mid -0.249642 0.249642)
							(end -0.2794 0.1778)
						)
						(arc
							(start -0.2794 -0.1778)
							(mid -0.249642 -0.249642)
							(end -0.1778 -0.2794)
						)
						(arc
							(start 0.1778 -0.2794)
							(mid 0.249642 -0.249642)
							(end 0.2794 -0.1778)
						)
						(arc
							(start 0.2794 0.1778)
							(mid 0.249642 0.249642)
							(end 0.1778 0.2794)
						)
					)
					(width 0)
					(fill yes)
				)
			)
		)
	)
	(footprint ""
		(layer "B.Cu")
		(at 56.843168 -163.069524 -90)
		(property "Reference" "R413"
			(at 0 0 90)
			(layer "B.SilkS")
			(hide yes)
			(effects
				(font
					(size 1.27 1.27)
				)
				(justify mirror)
			)
		)
		(property "Value" "2K7R2F-GP"
			(at -0.064008 -3.993896 270)
			(unlocked yes)
			(layer "B.Fab")
			(hide yes)
			(effects
				(font
					(size 1.016 1.016)
					(thickness 0.1524)
				)
				(justify mirror)
			)
		)
		(property "Device Type" "R402H16"
			(at -0.064008 -5.517896 270)
			(unlocked yes)
			(layer "B.Fab")
			(hide yes)
			(effects
				(font
					(size 1.016 1.016)
					(thickness 0.1524)
				)
				(justify mirror)
			)
		)
		(duplicate_pad_numbers_are_jumpers no)
		(fp_line
			(start -0.508 -0.9398)
			(end 0.508 -0.9398)
			(stroke
				(width 0.1524)
				(type default)
			)
			(layer "B.SilkS")
		)
		(fp_line
			(start 0.508 -0.9398)
			(end 0.508 0.9398)
			(stroke
				(width 0.1524)
				(type default)
			)
			(layer "B.SilkS")
		)
		(fp_rect
			(start 0.508 0.9398)
			(end -0.508 -0.9398)
			(stroke
				(width 0)
				(type default)
			)
			(fill no)
			(layer "B.CrtYd")
		)
		(fp_rect
			(start 0.508 0.9398)
			(end -0.508 -0.9398)
			(stroke
				(width 0)
				(type default)
			)
			(fill no)
			(layer "B.Fab")
		)
		(pad "1" smd custom
			(at 0 -0.4445 90)
			(size 0.1397 0.1397)
			(layers "B.Cu" "B.Mask" "B.Paste")
			(net "P5V_STBY")
			(options
				(clearance outline)
				(anchor circle)
			)
			(primitives
				(gr_poly
					(pts
						(arc
							(start -0.1778 0.2794)
							(mid -0.249642 0.249642)
							(end -0.2794 0.1778)
						)
						(arc
							(start -0.2794 -0.1778)
							(mid -0.249642 -0.249642)
							(end -0.1778 -0.2794)
						)
						(arc
							(start 0.1778 -0.2794)
							(mid 0.249642 -0.249642)
							(end 0.2794 -0.1778)
						)
						(arc
							(start 0.2794 0.1778)
							(mid 0.249642 0.249642)
							(end 0.1778 0.2794)
						)
					)
					(width 0)
					(fill yes)
				)
			)
		)
		(pad "2" smd custom
			(at 0 0.4445 90)
			(size 0.1397 0.1397)
			(layers "B.Cu" "B.Mask" "B.Paste")
			(net "ADC_P5V_STBY")
			(options
				(clearance outline)
				(anchor circle)
			)
			(primitives
				(gr_poly
					(pts
						(arc
							(start -0.1778 0.2794)
							(mid -0.249642 0.249642)
							(end -0.2794 0.1778)
						)
						(arc
							(start -0.2794 -0.1778)
							(mid -0.249642 -0.249642)
							(end -0.1778 -0.2794)
						)
						(arc
							(start 0.1778 -0.2794)
							(mid 0.249642 -0.249642)
							(end 0.2794 -0.1778)
						)
						(arc
							(start 0.2794 0.1778)
							(mid 0.249642 0.249642)
							(end 0.1778 0.2794)
						)
					)
					(width 0)
					(fill yes)
				)
			)
		)
	)
	(footprint ""
		(layer "B.Cu")
		(at 39.020496 -138.098276)
		(property "Reference" "TP17"
			(at 0 0 0)
			(layer "B.SilkS")
			(hide yes)
			(effects
				(font
					(size 1.27 1.27)
				)
				(justify mirror)
			)
		)
		(property "Value" "TPAD28-2-GP"
			(at 0.0127 -1.6637 0)
			(unlocked yes)
			(layer "B.Fab")
			(hide yes)
			(effects
				(font
					(size 1.016 1.016)
					(thickness 0.1524)
				)
				(justify mirror)
			)
		)
		(property "Device Type" "TPAD28"
			(at 0.0127 -3.1877 0)
			(unlocked yes)
			(layer "B.Fab")
			(hide yes)
			(effects
				(font
					(size 1.016 1.016)
					(thickness 0.1524)
				)
				(justify mirror)
			)
		)
		(duplicate_pad_numbers_are_jumpers no)
		(fp_poly
			(pts
				(arc
					(start 0.3556 0)
					(mid -0.3556 0)
					(end 0.3556 0)
				)
			)
			(stroke
				(width 0)
				(type default)
			)
			(fill no)
			(layer "B.CrtYd")
		)
		(fp_poly
			(pts
				(arc
					(start 0.6096 0)
					(mid -0.6096 0)
					(end 0.6096 0)
				)
			)
			(stroke
				(width 0)
				(type default)
			)
			(fill no)
			(layer "B.Fab")
		)
		(pad "1" smd circle
			(at 0 0 180)
			(size 0.7112 0.7112)
			(layers "B.Cu" "B.Mask" "B.Paste")
			(net "TP_BMC_GPIOR3")
		)
	)
	(footprint ""
		(layer "B.Cu")
		(at 167.28059 -38.416738)
		(property "Reference" "C501"
			(at 0 0 0)
			(layer "B.SilkS")
			(hide yes)
			(effects
				(font
					(size 1.27 1.27)
				)
				(justify mirror)
			)
		)
		(property "Value" "SCD01U16V1KX-GP"
			(at 2.8321 -1.7399 0)
			(unlocked yes)
			(layer "B.Fab")
			(hide yes)
			(effects
				(font
					(size 1.016 1.016)
					(thickness 0.1524)
				)
				(justify mirror)
			)
		)
		(property "Device Type" "C0201H13"
			(at 2.8321 -3.2639 0)
			(unlocked yes)
			(layer "B.Fab")
			(hide yes)
			(effects
				(font
					(size 1.016 1.016)
					(thickness 0.1524)
				)
				(justify mirror)
			)
		)
		(duplicate_pad_numbers_are_jumpers no)
		(fp_rect
			(start 0.2794 0.6477)
			(end -0.2794 -0.6477)
			(stroke
				(width 0)
				(type default)
			)
			(fill no)
			(layer "B.CrtYd")
		)
		(fp_rect
			(start 0.2794 0.6477)
			(end -0.2794 -0.6477)
			(stroke
				(width 0)
				(type default)
			)
			(fill no)
			(layer "B.Fab")
		)
		(pad "1" smd custom
			(at 0 -0.2794 180)
			(size 0.0762 0.0762)
			(layers "B.Cu" "B.Mask" "B.Paste")
			(net "PHY_CON_B_TO_IOC_2_DN")
			(options
				(clearance outline)
				(anchor circle)
			)
			(primitives
				(gr_poly
					(pts
						(arc
							(start 0.1524 0.127)
							(mid 0.137521 0.162921)
							(end 0.1016 0.1778)
						)
						(arc
							(start -0.1016 0.1778)
							(mid -0.137521 0.162921)
							(end -0.1524 0.127)
						)
						(arc
							(start -0.1524 -0.127)
							(mid -0.137521 -0.162921)
							(end -0.1016 -0.1778)
						)
						(arc
							(start 0.1016 -0.1778)
							(mid 0.137521 -0.162921)
							(end 0.1524 -0.127)
						)
					)
					(width 0)
					(fill yes)
				)
			)
		)
		(pad "2" smd custom
			(at 0 0.2794 180)
			(size 0.0762 0.0762)
			(layers "B.Cu" "B.Mask" "B.Paste")
			(net "PHY_CON_B_TO_IOC_2_DN_C")
			(options
				(clearance outline)
				(anchor circle)
			)
			(primitives
				(gr_poly
					(pts
						(arc
							(start 0.1524 0.127)
							(mid 0.137521 0.162921)
							(end 0.1016 0.1778)
						)
						(arc
							(start -0.1016 0.1778)
							(mid -0.137521 0.162921)
							(end -0.1524 0.127)
						)
						(arc
							(start -0.1524 -0.127)
							(mid -0.137521 -0.162921)
							(end -0.1016 -0.1778)
						)
						(arc
							(start 0.1016 -0.1778)
							(mid 0.137521 -0.162921)
							(end 0.1524 -0.127)
						)
					)
					(width 0)
					(fill yes)
				)
			)
		)
	)
	(footprint ""
		(layer "B.Cu")
		(at 90.2462 -173.5836 90)
		(property "Reference" "R417"
			(at 0 0 90)
			(layer "B.SilkS")
			(hide yes)
			(effects
				(font
					(size 1.27 1.27)
				)
				(justify mirror)
			)
		)
		(property "Value" "0R2J-2-GP"
			(at -0.064008 -3.993896 90)
			(unlocked yes)
			(layer "B.Fab")
			(hide yes)
			(effects
				(font
					(size 1.016 1.016)
					(thickness 0.1524)
				)
				(justify mirror)
			)
		)
		(property "Device Type" "R402H16"
			(at -0.064008 -5.517896 90)
			(unlocked yes)
			(layer "B.Fab")
			(hide yes)
			(effects
				(font
					(size 1.016 1.016)
					(thickness 0.1524)
				)
				(justify mirror)
			)
		)
		(duplicate_pad_numbers_are_jumpers no)
		(fp_line
			(start 0.508 -0.9398)
			(end 0.508 0.9398)
			(stroke
				(width 0.1524)
				(type default)
			)
			(layer "B.SilkS")
		)
		(fp_line
			(start -0.508 -0.9398)
			(end 0.508 -0.9398)
			(stroke
				(width 0.1524)
				(type default)
			)
			(layer "B.SilkS")
		)
		(fp_rect
			(start 0.508 0.9398)
			(end -0.508 -0.9398)
			(stroke
				(width 0)
				(type default)
			)
			(fill no)
			(layer "B.CrtYd")
		)
		(fp_rect
			(start 0.508 0.9398)
			(end -0.508 -0.9398)
			(stroke
				(width 0)
				(type default)
			)
			(fill no)
			(layer "B.Fab")
		)
		(pad "1" smd custom
			(at 0 -0.4445 270)
			(size 0.1397 0.1397)
			(layers "B.Cu" "B.Mask" "B.Paste")
			(net "PCIE_RST_R_N")
			(options
				(clearance outline)
				(anchor circle)
			)
			(primitives
				(gr_poly
					(pts
						(arc
							(start -0.1778 0.2794)
							(mid -0.249642 0.249642)
							(end -0.2794 0.1778)
						)
						(arc
							(start -0.2794 -0.1778)
							(mid -0.249642 -0.249642)
							(end -0.1778 -0.2794)
						)
						(arc
							(start 0.1778 -0.2794)
							(mid 0.249642 -0.249642)
							(end 0.2794 -0.1778)
						)
						(arc
							(start 0.2794 0.1778)
							(mid 0.249642 0.249642)
							(end 0.1778 0.2794)
						)
					)
					(width 0)
					(fill yes)
				)
			)
		)
		(pad "2" smd custom
			(at 0 0.4445 270)
			(size 0.1397 0.1397)
			(layers "B.Cu" "B.Mask" "B.Paste")
			(net "PCIE_COMP_TO_IOM_RST_4")
			(options
				(clearance outline)
				(anchor circle)
			)
			(primitives
				(gr_poly
					(pts
						(arc
							(start -0.1778 0.2794)
							(mid -0.249642 0.249642)
							(end -0.2794 0.1778)
						)
						(arc
							(start -0.2794 -0.1778)
							(mid -0.249642 -0.249642)
							(end -0.1778 -0.2794)
						)
						(arc
							(start 0.1778 -0.2794)
							(mid 0.249642 -0.249642)
							(end 0.2794 -0.1778)
						)
						(arc
							(start 0.2794 0.1778)
							(mid 0.249642 0.249642)
							(end 0.1778 0.2794)
						)
					)
					(width 0)
					(fill yes)
				)
			)
		)
	)
)
